(kicad_pcb
	(version 20260206)
	(generator "pcbnew")
	(generator_version "10.0")
	(general
		(thickness 1.6)
		(legacy_teardrops no)
	)
	(paper "A4")
	(title_block
		(title "timecard-production-celestica-r4006 — R4006-B0001-02_R01.brd")
		(comment 1 "Time Appliance Project (Time Card) / footprints 708-712 of 1113")
	)
	(layers
		(0 "F.Cu" signal "TOP")
		(4 "In1.Cu" signal "L02_GND1")
		(6 "In2.Cu" signal "L03_SIG1")
		(8 "In3.Cu" signal "L04_GND2")
		(10 "In4.Cu" signal "L05_VCC1")
		(12 "In5.Cu" signal "L06_VCC2")
		(14 "In6.Cu" signal "L07_GND3")
		(16 "In7.Cu" signal "L08_SIG2")
		(18 "In8.Cu" signal "L09_GND4")
		(2 "B.Cu" signal "BOTTOM")
		(9 "F.Adhes" user "F.Adhesive")
		(11 "B.Adhes" user "B.Adhesive")
		(13 "F.Paste" user "Package Geometry/Pastemask Top")
		(15 "B.Paste" user "Package Geometry/Pastemask Bottom")
		(5 "F.SilkS" user "Ref Des/Silkscreen Top")
		(7 "B.SilkS" user "Ref Des/Silkscreen Bottom")
		(1 "F.Mask" user "Board Geometry/Soldermask Top")
		(3 "B.Mask" user "Board Geometry/Soldermask Bottom")
		(17 "Dwgs.User" user "User.Drawings")
		(19 "Cmts.User" user "User.Comments")
		(21 "Eco1.User" user "User.Eco1")
		(23 "Eco2.User" user "User.Eco2")
		(25 "Edge.Cuts" user "Board Geometry/Outline")
		(27 "Margin" user)
		(31 "F.CrtYd" user "Package Geometry/Place Bound Top")
		(29 "B.CrtYd" user "Package Geometry/Place Bound Bottom")
		(35 "F.Fab" user "Ref Des/Assembly Top")
		(33 "B.Fab" user "Ref Des/Assembly Bottom")
	)
	(footprint ""
		(layer "B.Cu")
		(at 21.844 -20.6248 -90)
		(property "Reference" "C1"
			(at 0.9398 -1.10363 270)
			(unlocked yes)
			(layer "B.SilkS")
			(effects
				(font
					(size 0.7874 0.5842)
					(thickness 0.1524)
				)
				(justify mirror)
			)
		)
		(property "Value" "VAL*"
			(at -0.0762 2.067306 270)
			(unlocked yes)
			(layer "B.Fab")
			(hide yes)
			(effects
				(font
					(size 0.7874 0.5842)
					(thickness 0.1524)
				)
				(justify mirror)
			)
		)
		(property "Device Type" "CAPACITOR-G105-0B104-EK,0.1UF,A"
			(at -0.0508 1.127506 270)
			(unlocked yes)
			(layer "B.Fab")
			(hide yes)
			(effects
				(font
					(size 0.7874 0.5842)
					(thickness 0.1524)
				)
				(justify mirror)
			)
		)
		(property "User Part Number" "PARTNUM*"
			(at -0.1016 4.023106 270)
			(unlocked yes)
			(layer "Cmts.User")
			(hide yes)
			(effects
				(font
					(size 0.7874 0.5842)
					(thickness 0.1524)
				)
				(justify mirror)
			)
		)
		(property "Tolerance" "TOL*"
			(at -0.0762 3.032506 270)
			(unlocked yes)
			(layer "Cmts.User")
			(hide yes)
			(effects
				(font
					(size 0.7874 0.5842)
					(thickness 0.1524)
				)
				(justify mirror)
			)
		)
		(duplicate_pad_numbers_are_jumpers no)
		(fp_line
			(start -1.143 0.5588)
			(end -1.143 -0.5588)
			(stroke
				(width 0.1)
				(type default)
			)
			(layer "B.SilkS")
		)
		(fp_line
			(start 1.143 0.5588)
			(end -1.143 0.5588)
			(stroke
				(width 0.1)
				(type default)
			)
			(layer "B.SilkS")
		)
		(fp_line
			(start -1.143 -0.5588)
			(end 1.143 -0.5588)
			(stroke
				(width 0.1)
				(type default)
			)
			(layer "B.SilkS")
		)
		(fp_line
			(start 1.143 -0.5588)
			(end 1.143 0.5588)
			(stroke
				(width 0.1)
				(type default)
			)
			(layer "B.SilkS")
		)
		(fp_rect
			(start 1.143 0.5588)
			(end -1.143 -0.5588)
			(stroke
				(width 0)
				(type default)
			)
			(fill no)
			(layer "B.CrtYd")
		)
		(fp_line
			(start -0.508 0.3048)
			(end -0.508 -0.3048)
			(stroke
				(width 0.1)
				(type default)
			)
			(layer "B.Fab")
		)
		(fp_line
			(start 0.508 0.3048)
			(end -0.508 0.3048)
			(stroke
				(width 0.1)
				(type default)
			)
			(layer "B.Fab")
		)
		(fp_line
			(start -0.508 -0.3048)
			(end 0.508 -0.3048)
			(stroke
				(width 0.1)
				(type default)
			)
			(layer "B.Fab")
		)
		(fp_line
			(start 0.508 -0.3048)
			(end 0.508 0.3048)
			(stroke
				(width 0.1)
				(type default)
			)
			(layer "B.Fab")
		)
		(pad "1" smd rect
			(at 0.5334 0 90)
			(size 0.7112 0.6096)
			(layers "B.Cu" "B.Mask" "B.Paste")
			(net "XP3R3V_FPGA")
		)
		(pad "2" smd rect
			(at -0.5334 0 90)
			(size 0.7112 0.6096)
			(layers "B.Cu" "B.Mask" "B.Paste")
			(net "SG")
		)
		(zone
			(layer "B.Cu")
			(hatch none 0.5)
			(connect_pads
				(clearance 0)
			)
			(min_thickness 0.25)
			(keepout
				(tracks not_allowed)
				(vias allowed)
				(pads allowed)
				(copperpour not_allowed)
				(footprints allowed)
			)
			(placement
				(enabled no)
				(sheetname "")
			)
			(fill
				(thermal_gap 0.5)
				(thermal_bridge_width 0.5)
				(island_removal_mode 0)
			)
			(polygon
				(pts
					(xy 21.5392 -20.5486) (xy 22.1488 -20.5486) (xy 22.1488 -20.701) (xy 21.5392 -20.701)
				)
			)
		)
		(zone
			(layer "B.Cu")
			(hatch none 0.5)
			(connect_pads
				(clearance 0)
			)
			(min_thickness 0.25)
			(keepout
				(tracks allowed)
				(vias not_allowed)
				(pads allowed)
				(copperpour not_allowed)
				(footprints allowed)
			)
			(placement
				(enabled no)
				(sheetname "")
			)
			(fill
				(thermal_gap 0.5)
				(thermal_bridge_width 0.5)
				(island_removal_mode 0)
			)
			(polygon
				(pts
					(xy 21.5392 -20.5486) (xy 22.1488 -20.5486) (xy 22.1488 -20.701) (xy 21.5392 -20.701)
				)
			)
		)
	)
	(footprint ""
		(layer "B.Cu")
		(at 141.097 -59.563 -90)
		(property "Reference" "R246"
			(at -3.175 0.16637 270)
			(unlocked yes)
			(layer "B.SilkS")
			(effects
				(font
					(size 0.7874 0.5842)
					(thickness 0.1524)
				)
				(justify mirror)
			)
		)
		(property "Value" "VAL*"
			(at -0.02032 2.13233 270)
			(unlocked yes)
			(layer "B.Fab")
			(hide yes)
			(effects
				(font
					(size 0.7874 0.5842)
					(thickness 0.1524)
				)
				(justify mirror)
			)
		)
		(property "Device Type" "RESISTOR-A155-05101-DL,5.1KOHMA"
			(at -0.008382 1.210564 270)
			(unlocked yes)
			(layer "B.Fab")
			(hide yes)
			(effects
				(font
					(size 0.7874 0.5842)
					(thickness 0.1524)
				)
				(justify mirror)
			)
		)
		(property "User Part Number" "PARTNUM*"
			(at -0.02032 4.024884 270)
			(unlocked yes)
			(layer "Cmts.User")
			(hide yes)
			(effects
				(font
					(size 0.7874 0.5842)
					(thickness 0.1524)
				)
				(justify mirror)
			)
		)
		(property "Tolerance" "TOL*"
			(at -0.044704 3.05435 270)
			(unlocked yes)
			(layer "Cmts.User")
			(hide yes)
			(effects
				(font
					(size 0.7874 0.5842)
					(thickness 0.1524)
				)
				(justify mirror)
			)
		)
		(duplicate_pad_numbers_are_jumpers no)
		(fp_line
			(start -1.143 0.5588)
			(end -1.143 -0.5588)
			(stroke
				(width 0.1)
				(type default)
			)
			(layer "B.SilkS")
		)
		(fp_line
			(start 1.143 0.5588)
			(end -1.143 0.5588)
			(stroke
				(width 0.1)
				(type default)
			)
			(layer "B.SilkS")
		)
		(fp_line
			(start -1.143 -0.5588)
			(end 1.143 -0.5588)
			(stroke
				(width 0.1)
				(type default)
			)
			(layer "B.SilkS")
		)
		(fp_line
			(start 1.143 -0.5588)
			(end 1.143 0.5588)
			(stroke
				(width 0.1)
				(type default)
			)
			(layer "B.SilkS")
		)
		(fp_rect
			(start 1.143 0.5588)
			(end -1.143 -0.5588)
			(stroke
				(width 0)
				(type default)
			)
			(fill no)
			(layer "B.CrtYd")
		)
		(fp_line
			(start -0.508 0.3048)
			(end -0.508 -0.3048)
			(stroke
				(width 0.1)
				(type default)
			)
			(layer "B.Fab")
		)
		(fp_line
			(start 0.508 0.3048)
			(end -0.508 0.3048)
			(stroke
				(width 0.1)
				(type default)
			)
			(layer "B.Fab")
		)
		(fp_line
			(start -0.508 -0.3048)
			(end 0.508 -0.3048)
			(stroke
				(width 0.1)
				(type default)
			)
			(layer "B.Fab")
		)
		(fp_line
			(start 0.508 -0.3048)
			(end 0.508 0.3048)
			(stroke
				(width 0.1)
				(type default)
			)
			(layer "B.Fab")
		)
		(pad "1" smd rect
			(at 0.5334 0 90)
			(size 0.7112 0.6096)
			(layers "B.Cu" "B.Mask" "B.Paste")
			(net "UNNAMED_523_CAPACITOR_I7_1")
		)
		(pad "2" smd rect
			(at -0.5334 0 90)
			(size 0.7112 0.6096)
			(layers "B.Cu" "B.Mask" "B.Paste")
			(net "SG")
		)
		(zone
			(layer "B.Cu")
			(hatch none 0.5)
			(connect_pads
				(clearance 0)
			)
			(min_thickness 0.25)
			(keepout
				(tracks allowed)
				(vias not_allowed)
				(pads allowed)
				(copperpour not_allowed)
				(footprints allowed)
			)
			(placement
				(enabled no)
				(sheetname "")
			)
			(fill
				(thermal_gap 0.5)
				(thermal_bridge_width 0.5)
				(island_removal_mode 0)
			)
			(polygon
				(pts
					(xy 140.7922 -59.4868) (xy 141.4018 -59.4868) (xy 141.4018 -59.6392) (xy 140.7922 -59.6392)
				)
			)
		)
	)
	(footprint ""
		(layer "B.Cu")
		(at 72.39 -58.674 90)
		(property "Reference" "R357"
			(at 3.175 7.32663 270)
			(unlocked yes)
			(layer "B.SilkS")
			(effects
				(font
					(size 0.7874 0.5842)
					(thickness 0.1524)
				)
				(justify mirror)
			)
		)
		(property "Value" "VAL*"
			(at -0.0508 3.159506 90)
			(unlocked yes)
			(layer "B.Fab")
			(hide yes)
			(effects
				(font
					(size 0.7874 0.5842)
					(thickness 0.1524)
				)
				(justify mirror)
			)
		)
		(property "Tolerance" "TOL*"
			(at -0.0508 4.124706 90)
			(unlocked yes)
			(layer "Cmts.User")
			(hide yes)
			(effects
				(font
					(size 0.7874 0.5842)
					(thickness 0.1524)
				)
				(justify mirror)
			)
		)
		(property "User Part Number" "PARTNUM*"
			(at -0.0508 5.089906 90)
			(unlocked yes)
			(layer "Cmts.User")
			(hide yes)
			(effects
				(font
					(size 0.7874 0.5842)
					(thickness 0.1524)
				)
				(justify mirror)
			)
		)
		(property "Device Type" "RESISTOR-G157-100R0-J0,0OHM,-"
			(at 0 2.194306 90)
			(unlocked yes)
			(layer "B.Fab")
			(hide yes)
			(effects
				(font
					(size 0.7874 0.5842)
					(thickness 0.1524)
				)
				(justify mirror)
			)
		)
		(duplicate_pad_numbers_are_jumpers no)
		(fp_line
			(start 1.5748 -0.9398)
			(end 1.5748 0.9398)
			(stroke
				(width 0.1)
				(type default)
			)
			(layer "B.SilkS")
		)
		(fp_line
			(start -1.5748 -0.9398)
			(end 1.5748 -0.9398)
			(stroke
				(width 0.1)
				(type default)
			)
			(layer "B.SilkS")
		)
		(fp_line
			(start 1.5748 0.9398)
			(end -1.5748 0.9398)
			(stroke
				(width 0.1)
				(type default)
			)
			(layer "B.SilkS")
		)
		(fp_line
			(start -1.5748 0.9398)
			(end -1.5748 -0.9398)
			(stroke
				(width 0.1)
				(type default)
			)
			(layer "B.SilkS")
		)
		(fp_rect
			(start 1.5748 0.9398)
			(end -1.5748 -0.9398)
			(stroke
				(width 0)
				(type default)
			)
			(fill no)
			(layer "B.CrtYd")
		)
		(fp_line
			(start 1.016 -0.635)
			(end 1.016 0.635)
			(stroke
				(width 0.1)
				(type default)
			)
			(layer "B.Fab")
		)
		(fp_line
			(start -1.016 -0.635)
			(end 1.016 -0.635)
			(stroke
				(width 0.1)
				(type default)
			)
			(layer "B.Fab")
		)
		(fp_line
			(start 1.016 0.635)
			(end -1.016 0.635)
			(stroke
				(width 0.1)
				(type default)
			)
			(layer "B.Fab")
		)
		(fp_line
			(start -1.016 0.635)
			(end -1.016 -0.635)
			(stroke
				(width 0.1)
				(type default)
			)
			(layer "B.Fab")
		)
		(pad "1" smd rect
			(at 0.8382 0 270)
			(size 0.9652 1.3716)
			(layers "B.Cu" "B.Mask" "B.Paste")
			(net "XP5R0V_MAC")
		)
		(pad "2" smd rect
			(at -0.8382 0 270)
			(size 0.9652 1.3716)
			(layers "B.Cu" "B.Mask" "B.Paste")
			(net "UNNAMED_527_FUSE_I244_1")
		)
		(zone
			(layer "B.Cu")
			(hatch none 0.5)
			(connect_pads
				(clearance 0)
			)
			(min_thickness 0.25)
			(keepout
				(tracks not_allowed)
				(vias allowed)
				(pads allowed)
				(copperpour not_allowed)
				(footprints allowed)
			)
			(placement
				(enabled no)
				(sheetname "")
			)
			(fill
				(thermal_gap 0.5)
				(thermal_bridge_width 0.5)
				(island_removal_mode 0)
			)
			(polygon
				(pts
					(xy 73.025 -58.9026) (xy 71.755 -58.9026) (xy 71.755 -58.4454) (xy 73.025 -58.4454)
				)
			)
		)
		(zone
			(layer "B.Cu")
			(hatch none 0.5)
			(connect_pads
				(clearance 0)
			)
			(min_thickness 0.25)
			(keepout
				(tracks allowed)
				(vias not_allowed)
				(pads allowed)
				(copperpour not_allowed)
				(footprints allowed)
			)
			(placement
				(enabled no)
				(sheetname "")
			)
			(fill
				(thermal_gap 0.5)
				(thermal_bridge_width 0.5)
				(island_removal_mode 0)
			)
			(polygon
				(pts
					(xy 73.025 -58.9026) (xy 71.755 -58.9026) (xy 71.755 -58.4454) (xy 73.025 -58.4454)
				)
			)
		)
	)
	(footprint ""
		(layer "B.Cu")
		(at 143.383 -59.563 90)
		(property "Reference" "C263"
			(at 3.429 0.08763 270)
			(unlocked yes)
			(layer "B.SilkS")
			(effects
				(font
					(size 0.7874 0.5842)
					(thickness 0.1524)
				)
				(justify mirror)
			)
		)
		(property "Value" "VAL*"
			(at -0.193548 2.13614 90)
			(unlocked yes)
			(layer "B.Fab")
			(hide yes)
			(effects
				(font
					(size 0.7874 0.5842)
					(thickness 0.1524)
				)
				(justify mirror)
			)
		)
		(property "User Part Number" "PARTNUM*"
			(at -0.216154 4.185666 90)
			(unlocked yes)
			(layer "Cmts.User")
			(hide yes)
			(effects
				(font
					(size 0.7874 0.5842)
					(thickness 0.1524)
				)
				(justify mirror)
			)
		)
		(property "Device Type" "CAPACITOR-G104-0B472-EK,4700PFA"
			(at -0.184404 1.180592 90)
			(unlocked yes)
			(layer "B.Fab")
			(hide yes)
			(effects
				(font
					(size 0.7874 0.5842)
					(thickness 0.1524)
				)
				(justify mirror)
			)
		)
		(property "Tolerance" "TOL*"
			(at -0.216154 3.1496 90)
			(unlocked yes)
			(layer "Cmts.User")
			(hide yes)
			(effects
				(font
					(size 0.7874 0.5842)
					(thickness 0.1524)
				)
				(justify mirror)
			)
		)
		(duplicate_pad_numbers_are_jumpers no)
		(fp_line
			(start 0.671322 -0.4445)
			(end -0.671322 -0.4445)
			(stroke
				(width 0.1)
				(type default)
			)
			(layer "B.SilkS")
		)
		(fp_line
			(start -0.671322 -0.4445)
			(end -0.671322 0.4445)
			(stroke
				(width 0.1)
				(type default)
			)
			(layer "B.SilkS")
		)
		(fp_line
			(start 0.671322 0.4445)
			(end 0.671322 -0.4445)
			(stroke
				(width 0.1)
				(type default)
			)
			(layer "B.SilkS")
		)
		(fp_line
			(start -0.671322 0.4445)
			(end 0.671322 0.4445)
			(stroke
				(width 0.1)
				(type default)
			)
			(layer "B.SilkS")
		)
		(fp_rect
			(start 0.671322 0.4445)
			(end -0.671322 -0.4445)
			(stroke
				(width 0)
				(type default)
			)
			(fill no)
			(layer "B.CrtYd")
		)
		(fp_line
			(start 0.31496 -0.1651)
			(end 0.31496 0.1651)
			(stroke
				(width 0.1)
				(type default)
			)
			(layer "B.Fab")
		)
		(fp_line
			(start -0.31496 -0.1651)
			(end 0.31496 -0.1651)
			(stroke
				(width 0.1)
				(type default)
			)
			(layer "B.Fab")
		)
		(fp_line
			(start 0.31496 0.1651)
			(end -0.31496 0.1651)
			(stroke
				(width 0.1)
				(type default)
			)
			(layer "B.Fab")
		)
		(fp_line
			(start -0.31496 0.1651)
			(end -0.31496 -0.1651)
			(stroke
				(width 0.1)
				(type default)
			)
			(layer "B.Fab")
		)
		(pad "1" smd rect
			(at 0.264922 0 270)
			(size 0.3048 0.381)
			(layers "B.Cu" "B.Mask" "B.Paste")
			(net "UNNAMED_523_CAPACITOR_I9_1")
		)
		(pad "2" smd rect
			(at -0.264922 0 270)
			(size 0.3048 0.381)
			(layers "B.Cu" "B.Mask" "B.Paste")
			(net "XP1R0V_AGND")
		)
		(zone
			(layer "B.Cu")
			(hatch none 0.5)
			(connect_pads
				(clearance 0)
			)
			(min_thickness 0.25)
			(keepout
				(tracks allowed)
				(vias not_allowed)
				(pads allowed)
				(copperpour not_allowed)
				(footprints allowed)
			)
			(placement
				(enabled no)
				(sheetname "")
			)
			(fill
				(thermal_gap 0.5)
				(thermal_bridge_width 0.5)
				(island_removal_mode 0)
			)
			(polygon
				(pts
					(xy 143.1925 -59.675522) (xy 143.5735 -59.675522) (xy 143.5735 -59.450478) (xy 143.1925 -59.450478)
				)
			)
		)
		(zone
			(layer "B.Cu")
			(hatch none 0.5)
			(connect_pads
				(clearance 0)
			)
			(min_thickness 0.25)
			(keepout
				(tracks not_allowed)
				(vias allowed)
				(pads allowed)
				(copperpour not_allowed)
				(footprints allowed)
			)
			(placement
				(enabled no)
				(sheetname "")
			)
			(fill
				(thermal_gap 0.5)
				(thermal_bridge_width 0.5)
				(island_removal_mode 0)
			)
			(polygon
				(pts
					(xy 143.5735 -59.675522) (xy 143.5735 -59.450478) (xy 143.1925 -59.450478) (xy 143.1925 -59.675522)
				)
			)
		)
	)
	(footprint ""
		(layer "B.Cu")
		(at 107.347258 -39.823136 180)
		(property "Reference" "C141"
			(at 41.274238 -1.251966 0)
			(unlocked yes)
			(layer "B.SilkS")
			(effects
				(font
					(size 0.635 0.4064)
					(thickness 0.1524)
				)
				(justify mirror)
			)
		)
		(property "Value" "VAL*"
			(at 0 3.718306 180)
			(unlocked yes)
			(layer "B.Fab")
			(hide yes)
			(effects
				(font
					(size 0.7874 0.5842)
					(thickness 0.127)
				)
				(justify mirror)
			)
		)
		(property "Device Type" "CAPACITOR-G105-0B104-CK,0.1UF,A"
			(at 0 1.432306 180)
			(unlocked yes)
			(layer "B.Fab")
			(hide yes)
			(effects
				(font
					(size 0.7874 0.5842)
					(thickness 0.127)
				)
				(justify mirror)
			)
		)
		(property "User Part Number" "PARTNUM*"
			(at 0 2.575306 180)
			(unlocked yes)
			(layer "Cmts.User")
			(hide yes)
			(effects
				(font
					(size 0.7874 0.5842)
					(thickness 0.127)
				)
				(justify mirror)
			)
		)
		(property "Tolerance" "TOL*"
			(at 0 4.861306 180)
			(unlocked yes)
			(layer "Cmts.User")
			(hide yes)
			(effects
				(font
					(size 0.7874 0.5842)
					(thickness 0.127)
				)
				(justify mirror)
			)
		)
		(duplicate_pad_numbers_are_jumpers no)
		(fp_line
			(start 0.970026 0.4699)
			(end 0.970026 -0.4699)
			(stroke
				(width 0.1)
				(type default)
			)
			(layer "B.SilkS")
		)
		(fp_line
			(start 0.970026 -0.4699)
			(end -0.970026 -0.4699)
			(stroke
				(width 0.1)
				(type default)
			)
			(layer "B.SilkS")
		)
		(fp_line
			(start -0.970026 0.4699)
			(end 0.970026 0.4699)
			(stroke
				(width 0.1)
				(type default)
			)
			(layer "B.SilkS")
		)
		(fp_line
			(start -0.970026 -0.4699)
			(end -0.970026 0.4699)
			(stroke
				(width 0.1)
				(type default)
			)
			(layer "B.SilkS")
		)
		(fp_poly
			(pts
				(xy 0.970026 0.4699) (xy -0.970026 0.4699) (xy -0.970026 -0.4699) (xy 0.970026 -0.4699)
			)
			(stroke
				(width 0)
				(type default)
			)
			(fill no)
			(layer "B.CrtYd")
		)
		(fp_line
			(start 0.508 0.3048)
			(end 0.508 -0.3048)
			(stroke
				(width 0.1)
				(type default)
			)
			(layer "B.Fab")
		)
		(fp_line
			(start 0.508 -0.3048)
			(end -0.508 -0.3048)
			(stroke
				(width 0.1)
				(type default)
			)
			(layer "B.Fab")
		)
		(fp_line
			(start -0.508 0.3048)
			(end 0.508 0.3048)
			(stroke
				(width 0.1)
				(type default)
			)
			(layer "B.Fab")
		)
		(fp_line
			(start -0.508 -0.3048)
			(end -0.508 0.3048)
			(stroke
				(width 0.1)
				(type default)
			)
			(layer "B.Fab")
		)
		(pad "1" smd circle
			(at 0.500126 0)
			(size 0.635 0.635)
			(layers "B.Cu" "B.Mask" "B.Paste")
			(net "XP1R0V_FPGA_VCCINT")
		)
		(pad "2" smd circle
			(at -0.500126 0)
			(size 0.635 0.635)
			(layers "B.Cu" "B.Mask" "B.Paste")
			(net "SG")
		)
	)
)
